(kicad_pcb
	(version 20260206)
	(generator "pcbnew")
	(generator_version "10.0")
	(general
		(thickness 1.6)
		(legacy_teardrops no)
	)
	(paper "A4")
	(title_block
		(title "04192023_DAF0TMB3IC0_F0TG_MB_C_brd_V02_OCP.brd")
		(comment 1 "Grand Teton / footprints 2831-2834 of 8354")
	)
	(layers
		(0 "F.Cu" signal "TOP")
		(4 "In1.Cu" signal "GND")
		(6 "In2.Cu" signal "IN1")
		(8 "In3.Cu" signal "GND1")
		(10 "In4.Cu" signal "IN2")
		(12 "In5.Cu" signal "GND2")
		(14 "In6.Cu" signal "IN3")
		(16 "In7.Cu" signal "GND3")
		(18 "In8.Cu" signal "VCC")
		(20 "In9.Cu" signal "VCC1")
		(22 "In10.Cu" signal "GND4")
		(24 "In11.Cu" signal "IN4")
		(26 "In12.Cu" signal "GND5")
		(28 "In13.Cu" signal "IN5")
		(30 "In14.Cu" signal "GND6")
		(32 "In15.Cu" signal "IN6")
		(34 "In16.Cu" signal "GND7")
		(2 "B.Cu" signal "BOTTOM")
		(9 "F.Adhes" user "F.Adhesive")
		(11 "B.Adhes" user "B.Adhesive")
		(13 "F.Paste" user "Package Geometry/Pastemask Top")
		(15 "B.Paste" user "Package Geometry/Pastemask Bottom")
		(5 "F.SilkS" user "Ref Des/Silkscreen Top")
		(7 "B.SilkS" user "Ref Des/Silkscreen Bottom")
		(1 "F.Mask" user "Board Geometry/Soldermask Top")
		(3 "B.Mask" user "Board Geometry/Soldermask Bottom")
		(17 "Dwgs.User" user "User.Drawings")
		(19 "Cmts.User" user "User.Comments")
		(21 "Eco1.User" user "User.Eco1")
		(23 "Eco2.User" user "User.Eco2")
		(25 "Edge.Cuts" user "Board Geometry/Outline")
		(27 "Margin" user)
		(31 "F.CrtYd" user "Package Geometry/Place Bound Top")
		(29 "B.CrtYd" user "Package Geometry/Place Bound Bottom")
		(35 "F.Fab" user "Ref Des/Assembly Top")
		(33 "B.Fab" user "Ref Des/Assembly Bottom")
	)
	(footprint ""
		(layer "F.Cu")
		(at 56.958484 -408.517344 -90)
		(property "Reference" "C6636"
			(at 0 0 270)
			(layer "F.SilkS")
			(hide yes)
			(effects
				(font
					(size 1.27 1.27)
				)
			)
		)
		(property "Value" ""
			(at 0 0 270)
			(layer "F.Fab")
			(effects
				(font
					(size 1.27 1.27)
				)
			)
		)
		(duplicate_pad_numbers_are_jumpers no)
		(fp_line
			(start -0.299974 0.150114)
			(end -0.299974 -0.150114)
			(stroke
				(width 0.1)
				(type default)
			)
			(layer "F.Fab")
		)
		(fp_line
			(start 0.299974 0.150114)
			(end -0.299974 0.150114)
			(stroke
				(width 0.1)
				(type default)
			)
			(layer "F.Fab")
		)
		(fp_line
			(start -0.299974 -0.150114)
			(end 0.299974 -0.150114)
			(stroke
				(width 0.1)
				(type default)
			)
			(layer "F.Fab")
		)
		(fp_line
			(start 0.299974 -0.150114)
			(end 0.299974 0.150114)
			(stroke
				(width 0.1)
				(type default)
			)
			(layer "F.Fab")
		)
		(pad "1" smd rect
			(at -0.2667 0 270)
			(size 0.3048 0.381)
			(layers "F.Cu" "F.Mask" "F.Paste")
			(net "P5E_CPU1_P0_TX_BUF_C_DN<3>")
		)
		(pad "2" smd rect
			(at 0.2667 0 270)
			(size 0.3048 0.381)
			(layers "F.Cu" "F.Mask" "F.Paste")
			(net "P5E_CPU1_P0_TX_BUF_DN<3>")
		)
	)
	(footprint ""
		(layer "F.Cu")
		(at 392.840972 -387.853428)
		(property "Reference" "C871"
			(at 0 0 0)
			(layer "F.SilkS")
			(hide yes)
			(effects
				(font
					(size 1.27 1.27)
				)
			)
		)
		(property "Value" ""
			(at 0 0 0)
			(layer "F.Fab")
			(effects
				(font
					(size 1.27 1.27)
				)
			)
		)
		(duplicate_pad_numbers_are_jumpers no)
		(fp_line
			(start -0.299974 -0.150114)
			(end 0.299974 -0.150114)
			(stroke
				(width 0.1)
				(type default)
			)
			(layer "F.Fab")
		)
		(fp_line
			(start -0.299974 0.150114)
			(end -0.299974 -0.150114)
			(stroke
				(width 0.1)
				(type default)
			)
			(layer "F.Fab")
		)
		(fp_line
			(start 0.299974 -0.150114)
			(end 0.299974 0.150114)
			(stroke
				(width 0.1)
				(type default)
			)
			(layer "F.Fab")
		)
		(fp_line
			(start 0.299974 0.150114)
			(end -0.299974 0.150114)
			(stroke
				(width 0.1)
				(type default)
			)
			(layer "F.Fab")
		)
		(pad "1" smd rect
			(at -0.2667 0)
			(size 0.3048 0.381)
			(layers "F.Cu" "F.Mask" "F.Paste")
			(net "P5E_CPU0_P3_TX_C_DP<15>")
		)
		(pad "2" smd rect
			(at 0.2667 0)
			(size 0.3048 0.381)
			(layers "F.Cu" "F.Mask" "F.Paste")
			(net "P5E_CPU0_P3_TX_DP<15>")
		)
	)
	(footprint ""
		(layer "F.Cu")
		(at 150.373334 -121.826274)
		(property "Reference" "R4620"
			(at 0 0 0)
			(layer "F.SilkS")
			(hide yes)
			(effects
				(font
					(size 1.27 1.27)
				)
			)
		)
		(property "Value" ""
			(at 0 0 0)
			(layer "F.Fab")
			(effects
				(font
					(size 1.27 1.27)
				)
			)
		)
		(duplicate_pad_numbers_are_jumpers no)
		(fp_line
			(start -0.7874 -0.4064)
			(end 0.7874 -0.4064)
			(stroke
				(width 0.1524)
				(type default)
			)
			(layer "F.SilkS")
		)
		(fp_line
			(start -0.7874 0.4064)
			(end -0.7874 -0.4064)
			(stroke
				(width 0.1524)
				(type default)
			)
			(layer "F.SilkS")
		)
		(fp_line
			(start 0.7874 -0.4064)
			(end 0.7874 0.4064)
			(stroke
				(width 0.1524)
				(type default)
			)
			(layer "F.SilkS")
		)
		(fp_line
			(start 0.7874 0.4064)
			(end -0.7874 0.4064)
			(stroke
				(width 0.1524)
				(type default)
			)
			(layer "F.SilkS")
		)
		(fp_line
			(start -0.67945 -0.305054)
			(end -0.12065 -0.305054)
			(stroke
				(width 0.1)
				(type default)
			)
			(layer "F.Fab")
		)
		(fp_line
			(start -0.67945 0.3048)
			(end -0.67945 -0.305054)
			(stroke
				(width 0.1)
				(type default)
			)
			(layer "F.Fab")
		)
		(fp_line
			(start -0.12065 -0.305054)
			(end -0.12065 -0.2794)
			(stroke
				(width 0.1)
				(type default)
			)
			(layer "F.Fab")
		)
		(fp_line
			(start -0.12065 -0.2794)
			(end 0.12065 -0.2794)
			(stroke
				(width 0.1)
				(type default)
			)
			(layer "F.Fab")
		)
		(fp_line
			(start -0.12065 0.2794)
			(end -0.12065 0.3048)
			(stroke
				(width 0.1)
				(type default)
			)
			(layer "F.Fab")
		)
		(fp_line
			(start -0.12065 0.3048)
			(end -0.67945 0.3048)
			(stroke
				(width 0.1)
				(type default)
			)
			(layer "F.Fab")
		)
		(fp_line
			(start 0.120396 0.2794)
			(end -0.12065 0.2794)
			(stroke
				(width 0.1)
				(type default)
			)
			(layer "F.Fab")
		)
		(fp_line
			(start 0.120396 0.3048)
			(end 0.120396 0.2794)
			(stroke
				(width 0.1)
				(type default)
			)
			(layer "F.Fab")
		)
		(fp_line
			(start 0.12065 -0.3048)
			(end 0.67945 -0.3048)
			(stroke
				(width 0.1)
				(type default)
			)
			(layer "F.Fab")
		)
		(fp_line
			(start 0.12065 -0.2794)
			(end 0.12065 -0.3048)
			(stroke
				(width 0.1)
				(type default)
			)
			(layer "F.Fab")
		)
		(fp_line
			(start 0.67945 -0.3048)
			(end 0.67945 0.3048)
			(stroke
				(width 0.1)
				(type default)
			)
			(layer "F.Fab")
		)
		(fp_line
			(start 0.67945 0.3048)
			(end 0.120396 0.3048)
			(stroke
				(width 0.1)
				(type default)
			)
			(layer "F.Fab")
		)
		(pad "1" smd circle
			(at -0.40005 0)
			(size 0 0)
			(layers "F.Cu" "F.Mask" "F.Paste")
			(net "P3V3_AUX")
		)
		(pad "2" smd circle
			(at 0.40005 0)
			(size 0 0)
			(layers "F.Cu" "F.Mask" "F.Paste")
			(net "IRQ_UV_DETECT_N")
		)
	)
	(footprint ""
		(layer "F.Cu")
		(at 163.738814 -119.345202 180)
		(property "Reference" "R3486"
			(at 0 0 180)
			(layer "F.SilkS")
			(hide yes)
			(effects
				(font
					(size 1.27 1.27)
				)
			)
		)
		(property "Value" ""
			(at 0 0 180)
			(layer "F.Fab")
			(effects
				(font
					(size 1.27 1.27)
				)
			)
		)
		(duplicate_pad_numbers_are_jumpers no)
		(fp_line
			(start 0.7874 0.4064)
			(end -0.7874 0.4064)
			(stroke
				(width 0.1524)
				(type default)
			)
			(layer "F.SilkS")
		)
		(fp_line
			(start 0.7874 -0.4064)
			(end 0.7874 0.4064)
			(stroke
				(width 0.1524)
				(type default)
			)
			(layer "F.SilkS")
		)
		(fp_line
			(start -0.7874 0.4064)
			(end -0.7874 -0.4064)
			(stroke
				(width 0.1524)
				(type default)
			)
			(layer "F.SilkS")
		)
		(fp_line
			(start -0.7874 -0.4064)
			(end 0.7874 -0.4064)
			(stroke
				(width 0.1524)
				(type default)
			)
			(layer "F.SilkS")
		)
		(fp_line
			(start 0.67945 0.3048)
			(end 0.120396 0.3048)
			(stroke
				(width 0.1)
				(type default)
			)
			(layer "F.Fab")
		)
		(fp_line
			(start 0.67945 -0.3048)
			(end 0.67945 0.3048)
			(stroke
				(width 0.1)
				(type default)
			)
			(layer "F.Fab")
		)
		(fp_line
			(start 0.12065 -0.2794)
			(end 0.12065 -0.3048)
			(stroke
				(width 0.1)
				(type default)
			)
			(layer "F.Fab")
		)
		(fp_line
			(start 0.12065 -0.3048)
			(end 0.67945 -0.3048)
			(stroke
				(width 0.1)
				(type default)
			)
			(layer "F.Fab")
		)
		(fp_line
			(start 0.120396 0.3048)
			(end 0.120396 0.2794)
			(stroke
				(width 0.1)
				(type default)
			)
			(layer "F.Fab")
		)
		(fp_line
			(start 0.120396 0.2794)
			(end -0.12065 0.2794)
			(stroke
				(width 0.1)
				(type default)
			)
			(layer "F.Fab")
		)
		(fp_line
			(start -0.12065 0.3048)
			(end -0.67945 0.3048)
			(stroke
				(width 0.1)
				(type default)
			)
			(layer "F.Fab")
		)
		(fp_line
			(start -0.12065 0.2794)
			(end -0.12065 0.3048)
			(stroke
				(width 0.1)
				(type default)
			)
			(layer "F.Fab")
		)
		(fp_line
			(start -0.12065 -0.2794)
			(end 0.12065 -0.2794)
			(stroke
				(width 0.1)
				(type default)
			)
			(layer "F.Fab")
		)
		(fp_line
			(start -0.12065 -0.305054)
			(end -0.12065 -0.2794)
			(stroke
				(width 0.1)
				(type default)
			)
			(layer "F.Fab")
		)
		(fp_line
			(start -0.67945 0.3048)
			(end -0.67945 -0.305054)
			(stroke
				(width 0.1)
				(type default)
			)
			(layer "F.Fab")
		)
		(fp_line
			(start -0.67945 -0.305054)
			(end -0.12065 -0.305054)
			(stroke
				(width 0.1)
				(type default)
			)
			(layer "F.Fab")
		)
		(pad "1" smd circle
			(at -0.40005 0 180)
			(size 0 0)
			(layers "F.Cu" "F.Mask" "F.Paste")
			(net "GPU_PRSNT_N_ISO_R")
		)
		(pad "2" smd circle
			(at 0.40005 0 180)
			(size 0 0)
			(layers "F.Cu" "F.Mask" "F.Paste")
			(net "GPU_PRSNT_N_ISO")
		)
	)
)
